(kicad_pcb
	(version 20260206)
	(generator "pcbnew")
	(generator_version "10.0")
	(general
		(thickness 1.6)
		(legacy_teardrops no)
	)
	(paper "A4")
	(title_block
		(title "Wiwynn_Tioga_Pass_MB.brd")
		(comment 1 "Tioga Pass / footprints 1248-1250 of 4770")
	)
	(layers
		(0 "F.Cu" signal "TOP")
		(4 "In1.Cu" signal "L2GND")
		(6 "In2.Cu" signal "L3")
		(8 "In3.Cu" signal "L4GND")
		(10 "In4.Cu" signal "L5")
		(12 "In5.Cu" signal "L6GND")
		(14 "In6.Cu" signal "L7VCC")
		(16 "In7.Cu" signal "L8VCC")
		(18 "In8.Cu" signal "L9GND")
		(20 "In9.Cu" signal "L10")
		(22 "In10.Cu" signal "L11GND")
		(24 "In11.Cu" signal "L12")
		(26 "In12.Cu" signal "L13GND")
		(2 "B.Cu" signal "BOTTOM")
		(9 "F.Adhes" user "F.Adhesive")
		(11 "B.Adhes" user "B.Adhesive")
		(13 "F.Paste" user "Package Geometry/Pastemask Top")
		(15 "B.Paste" user "Package Geometry/Pastemask Bottom")
		(5 "F.SilkS" user "Ref Des/Silkscreen Top")
		(7 "B.SilkS" user "Ref Des/Silkscreen Bottom")
		(1 "F.Mask" user "Board Geometry/Soldermask Top")
		(3 "B.Mask" user "Board Geometry/Soldermask Bottom")
		(17 "Dwgs.User" user "User.Drawings")
		(19 "Cmts.User" user "User.Comments")
		(21 "Eco1.User" user "User.Eco1")
		(23 "Eco2.User" user "User.Eco2")
		(25 "Edge.Cuts" user "Board Geometry/Outline")
		(27 "Margin" user)
		(31 "F.CrtYd" user "Package Geometry/Place Bound Top")
		(29 "B.CrtYd" user "Package Geometry/Place Bound Bottom")
		(35 "F.Fab" user "Ref Des/Assembly Top")
		(33 "B.Fab" user "Ref Des/Assembly Bottom")
	)
	(footprint ""
		(layer "F.Cu")
		(at 275.708872 -73.318116)
		(property "Reference" "C5D50"
			(at 0 0 0)
			(layer "F.SilkS")
			(hide yes)
			(effects
				(font
					(size 1.27 1.27)
				)
			)
		)
		(property "Value" ""
			(at 0 0 0)
			(layer "F.Fab")
			(effects
				(font
					(size 1.27 1.27)
				)
			)
		)
		(duplicate_pad_numbers_are_jumpers no)
		(fp_poly
			(pts
				(xy -0.4953 -0.2032) (xy 0.4953 -0.2032) (xy 0.4953 1.6002) (xy -0.4953 1.6002)
			)
			(stroke
				(width 0)
				(type default)
			)
			(fill no)
			(layer "F.CrtYd")
		)
		(fp_line
			(start -0.4953 -0.2032)
			(end 0.4953 -0.2032)
			(stroke
				(width 0.1)
				(type default)
			)
			(layer "F.Fab")
		)
		(fp_line
			(start -0.4953 1.6002)
			(end -0.4953 -0.2032)
			(stroke
				(width 0.1)
				(type default)
			)
			(layer "F.Fab")
		)
		(fp_line
			(start 0.4953 -0.2032)
			(end 0.4953 1.6002)
			(stroke
				(width 0.1)
				(type default)
			)
			(layer "F.Fab")
		)
		(fp_line
			(start 0.4953 1.6002)
			(end -0.4953 1.6002)
			(stroke
				(width 0.1)
				(type default)
			)
			(layer "F.Fab")
		)
		(pad "1" smd rect
			(at 0 0)
			(size 0.762 0.889)
			(layers "F.Cu" "F.Mask" "F.Paste")
			(net "PVCCMCP_CPU0")
		)
		(pad "2" smd rect
			(at 0 1.397)
			(size 0.762 0.889)
			(layers "F.Cu" "F.Mask" "F.Paste")
			(net "GND")
		)
		(zone
			(layer "F.Cu")
			(hatch none 0.5)
			(connect_pads
				(clearance 0)
			)
			(min_thickness 0.25)
			(keepout
				(tracks not_allowed)
				(vias allowed)
				(pads allowed)
				(copperpour not_allowed)
				(footprints allowed)
			)
			(placement
				(enabled no)
				(sheetname "")
			)
			(fill
				(thermal_gap 0.5)
				(thermal_bridge_width 0.5)
				(island_removal_mode 0)
			)
			(polygon
				(pts
					(xy 275.327872 -72.873616) (xy 276.089872 -72.873616) (xy 276.089872 -72.365616) (xy 275.327872 -72.365616)
				)
			)
		)
	)
	(footprint ""
		(layer "F.Cu")
		(at 167.3098 -6.5024 180)
		(property "Reference" "C4G12"
			(at 0 0 180)
			(layer "F.SilkS")
			(hide yes)
			(effects
				(font
					(size 1.27 1.27)
				)
			)
		)
		(property "Value" ""
			(at 0 0 180)
			(layer "F.Fab")
			(effects
				(font
					(size 1.27 1.27)
				)
			)
		)
		(duplicate_pad_numbers_are_jumpers no)
		(fp_rect
			(start -0.3048 -0.1016)
			(end 0.3048 0.9906)
			(stroke
				(width 0)
				(type default)
			)
			(fill no)
			(layer "F.CrtYd")
		)
		(fp_line
			(start 0.3048 0.9906)
			(end 0.3048 -0.1016)
			(stroke
				(width 0.1)
				(type default)
			)
			(layer "F.Fab")
		)
		(fp_line
			(start 0.3048 -0.1016)
			(end -0.3048 -0.1016)
			(stroke
				(width 0.1)
				(type default)
			)
			(layer "F.Fab")
		)
		(fp_line
			(start -0.3048 0.9906)
			(end 0.3048 0.9906)
			(stroke
				(width 0.1)
				(type default)
			)
			(layer "F.Fab")
		)
		(fp_line
			(start -0.3048 -0.1016)
			(end -0.3048 0.9906)
			(stroke
				(width 0.1)
				(type default)
			)
			(layer "F.Fab")
		)
		(pad "1" smd rect
			(at 0 0 180)
			(size 0.508 0.508)
			(layers "F.Cu" "F.Mask" "F.Paste")
			(net "FM_PVTT_GHJ_EN_R")
		)
		(pad "2" smd rect
			(at 0 0.889 180)
			(size 0.508 0.508)
			(layers "F.Cu" "F.Mask" "F.Paste")
			(net "GND")
		)
		(zone
			(layer "F.Cu")
			(hatch none 0.5)
			(connect_pads
				(clearance 0)
			)
			(min_thickness 0.25)
			(keepout
				(tracks not_allowed)
				(vias allowed)
				(pads allowed)
				(copperpour not_allowed)
				(footprints allowed)
			)
			(placement
				(enabled no)
				(sheetname "")
			)
			(fill
				(thermal_gap 0.5)
				(thermal_bridge_width 0.5)
				(island_removal_mode 0)
			)
			(polygon
				(pts
					(xy 167.5638 -6.7564) (xy 167.5638 -7.1374) (xy 167.0558 -7.1374) (xy 167.0558 -6.7564)
				)
			)
		)
		(zone
			(layer "F.Cu")
			(hatch none 0.5)
			(connect_pads
				(clearance 0)
			)
			(min_thickness 0.25)
			(keepout
				(tracks allowed)
				(vias not_allowed)
				(pads allowed)
				(copperpour not_allowed)
				(footprints allowed)
			)
			(placement
				(enabled no)
				(sheetname "")
			)
			(fill
				(thermal_gap 0.5)
				(thermal_bridge_width 0.5)
				(island_removal_mode 0)
			)
			(polygon
				(pts
					(xy 167.5638 -6.7564) (xy 167.5638 -7.1374) (xy 167.0558 -7.1374) (xy 167.0558 -6.7564)
				)
			)
		)
	)
	(footprint ""
		(layer "F.Cu")
		(at 13.941806 2.692654 90)
		(property "Reference" "C1G22"
			(at 0 0 90)
			(layer "F.SilkS")
			(hide yes)
			(effects
				(font
					(size 1.27 1.27)
				)
			)
		)
		(property "Value" ""
			(at 0 0 90)
			(layer "F.Fab")
			(effects
				(font
					(size 1.27 1.27)
				)
			)
		)
		(duplicate_pad_numbers_are_jumpers no)
		(fp_rect
			(start 0.3048 -0.1016)
			(end -0.3048 0.9906)
			(stroke
				(width 0)
				(type default)
			)
			(fill no)
			(layer "F.CrtYd")
		)
		(fp_line
			(start 0.3048 -0.1016)
			(end -0.3048 -0.1016)
			(stroke
				(width 0.1)
				(type default)
			)
			(layer "F.Fab")
		)
		(fp_line
			(start -0.3048 -0.1016)
			(end -0.3048 0.9906)
			(stroke
				(width 0.1)
				(type default)
			)
			(layer "F.Fab")
		)
		(fp_line
			(start 0.3048 0.9906)
			(end 0.3048 -0.1016)
			(stroke
				(width 0.1)
				(type default)
			)
			(layer "F.Fab")
		)
		(fp_line
			(start -0.3048 0.9906)
			(end 0.3048 0.9906)
			(stroke
				(width 0.1)
				(type default)
			)
			(layer "F.Fab")
		)
		(pad "1" smd rect
			(at 0 0 90)
			(size 0.508 0.508)
			(layers "F.Cu" "F.Mask" "F.Paste")
			(net "VR_PVDDQ_GHJ_VD12")
		)
		(pad "2" smd rect
			(at 0 0.889 90)
			(size 0.508 0.508)
			(layers "F.Cu" "F.Mask" "F.Paste")
			(net "GND")
		)
		(zone
			(layer "F.Cu")
			(hatch none 0.5)
			(connect_pads
				(clearance 0)
			)
			(min_thickness 0.25)
			(keepout
				(tracks not_allowed)
				(vias allowed)
				(pads allowed)
				(copperpour not_allowed)
				(footprints allowed)
			)
			(placement
				(enabled no)
				(sheetname "")
			)
			(fill
				(thermal_gap 0.5)
				(thermal_bridge_width 0.5)
				(island_removal_mode 0)
			)
			(polygon
				(pts
					(xy 14.195806 2.438654) (xy 14.195806 2.946654) (xy 14.576806 2.946654) (xy 14.576806 2.438654)
				)
			)
		)
		(zone
			(layer "F.Cu")
			(hatch none 0.5)
			(connect_pads
				(clearance 0)
			)
			(min_thickness 0.25)
			(keepout
				(tracks allowed)
				(vias not_allowed)
				(pads allowed)
				(copperpour not_allowed)
				(footprints allowed)
			)
			(placement
				(enabled no)
				(sheetname "")
			)
			(fill
				(thermal_gap 0.5)
				(thermal_bridge_width 0.5)
				(island_removal_mode 0)
			)
			(polygon
				(pts
					(xy 14.195806 2.438654) (xy 14.195806 2.946654) (xy 14.576806 2.946654) (xy 14.576806 2.438654)
				)
			)
		)
	)
)
